# T6G (Grand Teton) — schematic netlist excerpt (pin names and nets, part order shuffled) for the footprints in the layout excerpt that follows; sources: Cadence DE-HDL packaged netlist, KiCad conversion of 04192023_DAF0TMB3IC0_F0TG_MB_C_brd_V02_OCP.brd

PR6522  Q_RES  7.15K 1% CHIP  pkg 0402LF  page 361 : A = P1V8_RETIMER_CPU1_CS ; B = GND
R1775  Q_RES  1K 1% CHIP  pkg 0402LF  page 187 : A = P3V_BAT ; B = P3V_BAT_R

(kicad_pcb
	(version 20260206)
	(generator "pcbnew")
	(generator_version "10.0")
	(general
		(thickness 1.6)
		(legacy_teardrops no)
	)
	(paper "A4")
	(title_block
		(title "04192023_DAF0TMB3IC0_F0TG_MB_C_brd_V02_OCP.brd")
		(comment 1 "Grand Teton / footprints 743-744 of 8354")
	)
	(layers
		(0 "F.Cu" signal "TOP")
		(4 "In1.Cu" signal "GND")
		(6 "In2.Cu" signal "IN1")
		(8 "In3.Cu" signal "GND1")
		(10 "In4.Cu" signal "IN2")
		(12 "In5.Cu" signal "GND2")
		(14 "In6.Cu" signal "IN3")
		(16 "In7.Cu" signal "GND3")
		(18 "In8.Cu" signal "VCC")
		(20 "In9.Cu" signal "VCC1")
		(22 "In10.Cu" signal "GND4")
		(24 "In11.Cu" signal "IN4")
		(26 "In12.Cu" signal "GND5")
		(28 "In13.Cu" signal "IN5")
		(30 "In14.Cu" signal "GND6")
		(32 "In15.Cu" signal "IN6")
		(34 "In16.Cu" signal "GND7")
		(2 "B.Cu" signal "BOTTOM")
		(9 "F.Adhes" user "F.Adhesive")
		(11 "B.Adhes" user "B.Adhesive")
		(13 "F.Paste" user "Package Geometry/Pastemask Top")
		(15 "B.Paste" user "Package Geometry/Pastemask Bottom")
		(5 "F.SilkS" user "Ref Des/Silkscreen Top")
		(7 "B.SilkS" user "Ref Des/Silkscreen Bottom")
		(1 "F.Mask" user "Board Geometry/Soldermask Top")
		(3 "B.Mask" user "Board Geometry/Soldermask Bottom")
		(17 "Dwgs.User" user "User.Drawings")
		(19 "Cmts.User" user "User.Comments")
		(21 "Eco1.User" user "User.Eco1")
		(23 "Eco2.User" user "User.Eco2")
		(25 "Edge.Cuts" user "Board Geometry/Outline")
		(27 "Margin" user)
		(31 "F.CrtYd" user "Package Geometry/Place Bound Top")
		(29 "B.CrtYd" user "Package Geometry/Place Bound Bottom")
		(35 "F.Fab" user "Ref Des/Assembly Top")
		(33 "B.Fab" user "Ref Des/Assembly Bottom")
	)
	(footprint ""
		(layer "F.Cu")
		(at 227.59162 -292.988238 180)
		(property "Reference" "PR6522"
			(at 0 0 180)
			(layer "F.SilkS")
			(hide yes)
			(effects
				(font
					(size 1.27 1.27)
				)
			)
		)
		(property "Value" ""
			(at 0 0 180)
			(layer "F.Fab")
			(effects
				(font
					(size 1.27 1.27)
				)
			)
		)
		(duplicate_pad_numbers_are_jumpers no)
		(fp_line
			(start 0.7874 0.4064)
			(end -0.7874 0.4064)
			(stroke
				(width 0.1524)
				(type default)
			)
			(layer "F.SilkS")
		)
		(fp_line
			(start 0.7874 -0.4064)
			(end 0.7874 0.4064)
			(stroke
				(width 0.1524)
				(type default)
			)
			(layer "F.SilkS")
		)
		(fp_line
			(start -0.7874 0.4064)
			(end -0.7874 -0.4064)
			(stroke
				(width 0.1524)
				(type default)
			)
			(layer "F.SilkS")
		)
		(fp_line
			(start -0.7874 -0.4064)
			(end 0.7874 -0.4064)
			(stroke
				(width 0.1524)
				(type default)
			)
			(layer "F.SilkS")
		)
		(fp_line
			(start 0.67945 0.3048)
			(end 0.120396 0.3048)
			(stroke
				(width 0.1)
				(type default)
			)
			(layer "F.Fab")
		)
		(fp_line
			(start 0.67945 -0.3048)
			(end 0.67945 0.3048)
			(stroke
				(width 0.1)
				(type default)
			)
			(layer "F.Fab")
		)
		(fp_line
			(start 0.12065 -0.2794)
			(end 0.12065 -0.3048)
			(stroke
				(width 0.1)
				(type default)
			)
			(layer "F.Fab")
		)
		(fp_line
			(start 0.12065 -0.3048)
			(end 0.67945 -0.3048)
			(stroke
				(width 0.1)
				(type default)
			)
			(layer "F.Fab")
		)
		(fp_line
			(start 0.120396 0.3048)
			(end 0.120396 0.2794)
			(stroke
				(width 0.1)
				(type default)
			)
			(layer "F.Fab")
		)
		(fp_line
			(start 0.120396 0.2794)
			(end -0.12065 0.2794)
			(stroke
				(width 0.1)
				(type default)
			)
			(layer "F.Fab")
		)
		(fp_line
			(start -0.12065 0.3048)
			(end -0.67945 0.3048)
			(stroke
				(width 0.1)
				(type default)
			)
			(layer "F.Fab")
		)
		(fp_line
			(start -0.12065 0.2794)
			(end -0.12065 0.3048)
			(stroke
				(width 0.1)
				(type default)
			)
			(layer "F.Fab")
		)
		(fp_line
			(start -0.12065 -0.2794)
			(end 0.12065 -0.2794)
			(stroke
				(width 0.1)
				(type default)
			)
			(layer "F.Fab")
		)
		(fp_line
			(start -0.12065 -0.305054)
			(end -0.12065 -0.2794)
			(stroke
				(width 0.1)
				(type default)
			)
			(layer "F.Fab")
		)
		(fp_line
			(start -0.67945 0.3048)
			(end -0.67945 -0.305054)
			(stroke
				(width 0.1)
				(type default)
			)
			(layer "F.Fab")
		)
		(fp_line
			(start -0.67945 -0.305054)
			(end -0.12065 -0.305054)
			(stroke
				(width 0.1)
				(type default)
			)
			(layer "F.Fab")
		)
		(pad "1" smd circle
			(at -0.40005 0 180)
			(size 0 0)
			(layers "F.Cu" "F.Mask" "F.Paste")
			(net "P1V8_RETIMER_CPU1_CS")
		)
		(pad "2" smd circle
			(at 0.40005 0 180)
			(size 0 0)
			(layers "F.Cu" "F.Mask" "F.Paste")
			(net "GND")
		)
	)
	(footprint ""
		(layer "F.Cu")
		(at 305.754024 -34.001964)
		(property "Reference" "R1775"
			(at 0 0 0)
			(layer "F.SilkS")
			(hide yes)
			(effects
				(font
					(size 1.27 1.27)
				)
			)
		)
		(property "Value" ""
			(at 0 0 0)
			(layer "F.Fab")
			(effects
				(font
					(size 1.27 1.27)
				)
			)
		)
		(duplicate_pad_numbers_are_jumpers no)
		(fp_line
			(start -0.7874 -0.4064)
			(end 0.7874 -0.4064)
			(stroke
				(width 0.1524)
				(type default)
			)
			(layer "F.SilkS")
		)
		(fp_line
			(start -0.7874 0.4064)
			(end -0.7874 -0.4064)
			(stroke
				(width 0.1524)
				(type default)
			)
			(layer "F.SilkS")
		)
		(fp_line
			(start 0.7874 -0.4064)
			(end 0.7874 0.4064)
			(stroke
				(width 0.1524)
				(type default)
			)
			(layer "F.SilkS")
		)
		(fp_line
			(start 0.7874 0.4064)
			(end -0.7874 0.4064)
			(stroke
				(width 0.1524)
				(type default)
			)
			(layer "F.SilkS")
		)
		(fp_line
			(start -0.67945 -0.305054)
			(end -0.12065 -0.305054)
			(stroke
				(width 0.1)
				(type default)
			)
			(layer "F.Fab")
		)
		(fp_line
			(start -0.67945 0.3048)
			(end -0.67945 -0.305054)
			(stroke
				(width 0.1)
				(type default)
			)
			(layer "F.Fab")
		)
		(fp_line
			(start -0.12065 -0.305054)
			(end -0.12065 -0.2794)
			(stroke
				(width 0.1)
				(type default)
			)
			(layer "F.Fab")
		)
		(fp_line
			(start -0.12065 -0.2794)
			(end 0.12065 -0.2794)
			(stroke
				(width 0.1)
				(type default)
			)
			(layer "F.Fab")
		)
		(fp_line
			(start -0.12065 0.2794)
			(end -0.12065 0.3048)
			(stroke
				(width 0.1)
				(type default)
			)
			(layer "F.Fab")
		)
		(fp_line
			(start -0.12065 0.3048)
			(end -0.67945 0.3048)
			(stroke
				(width 0.1)
				(type default)
			)
			(layer "F.Fab")
		)
		(fp_line
			(start 0.120396 0.2794)
			(end -0.12065 0.2794)
			(stroke
				(width 0.1)
				(type default)
			)
			(layer "F.Fab")
		)
		(fp_line
			(start 0.120396 0.3048)
			(end 0.120396 0.2794)
			(stroke
				(width 0.1)
				(type default)
			)
			(layer "F.Fab")
		)
		(fp_line
			(start 0.12065 -0.3048)
			(end 0.67945 -0.3048)
			(stroke
				(width 0.1)
				(type default)
			)
			(layer "F.Fab")
		)
		(fp_line
			(start 0.12065 -0.2794)
			(end 0.12065 -0.3048)
			(stroke
				(width 0.1)
				(type default)
			)
			(layer "F.Fab")
		)
		(fp_line
			(start 0.67945 -0.3048)
			(end 0.67945 0.3048)
			(stroke
				(width 0.1)
				(type default)
			)
			(layer "F.Fab")
		)
		(fp_line
			(start 0.67945 0.3048)
			(end 0.120396 0.3048)
			(stroke
				(width 0.1)
				(type default)
			)
			(layer "F.Fab")
		)
		(pad "1" smd circle
			(at -0.40005 0)
			(size 0 0)
			(layers "F.Cu" "F.Mask" "F.Paste")
			(net "P3V_BAT")
		)
		(pad "2" smd circle
			(at 0.40005 0)
			(size 0 0)
			(layers "F.Cu" "F.Mask" "F.Paste")
			(net "P3V_BAT_R")
		)
	)
)
